#ISCELL
  pure_quanta quanta_title_block_c *
  *
#ISCELL
  pure_quanta_power universal_gnd *
  page60_i1
#ISCELL
  pure_quanta_power universal_gnd *
  page60_i2
#CELL
  pure_quanta genoa_sp5 *
  page60_i3
